(kicad_pcb
	(version 20260206)
	(generator "pcbnew")
	(generator_version "10.0")
	(general
		(thickness 1.6)
		(legacy_teardrops no)
	)
	(paper "A4")
	(title_block
		(title "v1-chassis-manager — T6M_CM_d_v01_1031_1645.brd")
		(comment 1 "Open CloudServer (Microsoft) / footprints 1039-1044 of 2512")
	)
	(layers
		(0 "F.Cu" signal "TOP")
		(4 "In1.Cu" signal "GND1")
		(6 "In2.Cu" signal "IN1")
		(8 "In3.Cu" signal "VCC1")
		(10 "In4.Cu" signal "VCC2")
		(12 "In5.Cu" signal "GND2")
		(14 "In6.Cu" signal "IN2")
		(16 "In7.Cu" signal "IN3")
		(18 "In8.Cu" signal "GND3")
		(2 "B.Cu" signal "BOTTOM")
		(9 "F.Adhes" user "F.Adhesive")
		(11 "B.Adhes" user "B.Adhesive")
		(13 "F.Paste" user "Package Geometry/Pastemask Top")
		(15 "B.Paste" user "Package Geometry/Pastemask Bottom")
		(5 "F.SilkS" user "Ref Des/Silkscreen Top")
		(7 "B.SilkS" user "Ref Des/Silkscreen Bottom")
		(1 "F.Mask" user "Board Geometry/Soldermask Top")
		(3 "B.Mask" user "Board Geometry/Soldermask Bottom")
		(17 "Dwgs.User" user "User.Drawings")
		(19 "Cmts.User" user "User.Comments")
		(21 "Eco1.User" user "User.Eco1")
		(23 "Eco2.User" user "User.Eco2")
		(25 "Edge.Cuts" user "Board Geometry/Outline")
		(27 "Margin" user)
		(31 "F.CrtYd" user "Package Geometry/Place Bound Top")
		(29 "B.CrtYd" user "Package Geometry/Place Bound Bottom")
		(35 "F.Fab" user "Ref Des/Assembly Top")
		(33 "B.Fab" user "Ref Des/Assembly Bottom")
	)
	(footprint ""
		(layer "F.Cu")
		(at 94.451932 -174.306992)
		(property "Reference" "R754"
			(at 86.67369 74.174096 0)
			(unlocked yes)
			(layer "F.SilkS")
			(effects
				(font
					(size 0.7874 0.5842)
					(thickness 0.1524)
				)
				(justify left)
			)
		)
		(property "Value" ""
			(at 0 0 0)
			(layer "F.Fab")
			(effects
				(font
					(size 1.27 1.27)
				)
			)
		)
		(duplicate_pad_numbers_are_jumpers no)
		(fp_line
			(start -0.7874 -0.4064)
			(end 0.7874 -0.4064)
			(stroke
				(width 0.1524)
				(type default)
			)
			(layer "F.SilkS")
		)
		(fp_line
			(start -0.7874 0.4064)
			(end -0.7874 -0.4064)
			(stroke
				(width 0.1524)
				(type default)
			)
			(layer "F.SilkS")
		)
		(fp_line
			(start 0.7874 -0.4064)
			(end 0.7874 0.4064)
			(stroke
				(width 0.1524)
				(type default)
			)
			(layer "F.SilkS")
		)
		(fp_line
			(start 0.7874 0.4064)
			(end -0.7874 0.4064)
			(stroke
				(width 0.1524)
				(type default)
			)
			(layer "F.SilkS")
		)
		(fp_poly
			(pts
				(xy -0.508 0.2794) (xy -0.508 0.2286) (xy -0.635 0.2286) (xy -0.635 -0.254) (xy -0.5334 -0.254)
				(xy -0.5334 -0.2794) (xy 0.5334 -0.2794) (xy 0.5334 -0.254) (xy 0.635 -0.254) (xy 0.635 0.254) (xy 0.5334 0.254)
				(xy 0.5334 0.2794)
			)
			(stroke
				(width 0)
				(type default)
			)
			(fill no)
			(layer "F.CrtYd")
		)
		(pad "1" smd rect
			(at 0.40005 0)
			(size 0.4572 0.508)
			(layers "F.Cu" "F.Mask" "F.Paste")
			(net "N21698906")
		)
		(pad "2" smd rect
			(at -0.40005 0)
			(size 0.4572 0.508)
			(layers "F.Cu" "F.Mask" "F.Paste")
			(net "GND")
		)
	)
	(footprint ""
		(layer "F.Cu")
		(at 82.408014 -74.724006 -90)
		(property "Reference" "R113"
			(at 16.256508 -1.86055 90)
			(unlocked yes)
			(layer "F.SilkS")
			(effects
				(font
					(size 0.7874 0.5842)
					(thickness 0.1524)
				)
				(justify left)
			)
		)
		(property "Value" ""
			(at 0 0 270)
			(layer "F.Fab")
			(effects
				(font
					(size 1.27 1.27)
				)
			)
		)
		(duplicate_pad_numbers_are_jumpers no)
		(fp_line
			(start -0.7874 0.4064)
			(end -0.7874 -0.4064)
			(stroke
				(width 0.1524)
				(type default)
			)
			(layer "F.SilkS")
		)
		(fp_line
			(start 0.7874 0.4064)
			(end -0.7874 0.4064)
			(stroke
				(width 0.1524)
				(type default)
			)
			(layer "F.SilkS")
		)
		(fp_line
			(start -0.7874 -0.4064)
			(end 0.7874 -0.4064)
			(stroke
				(width 0.1524)
				(type default)
			)
			(layer "F.SilkS")
		)
		(fp_line
			(start 0.7874 -0.4064)
			(end 0.7874 0.4064)
			(stroke
				(width 0.1524)
				(type default)
			)
			(layer "F.SilkS")
		)
		(fp_poly
			(pts
				(xy -0.508 0.2794) (xy -0.508 0.2286) (xy -0.635 0.2286) (xy -0.635 -0.254) (xy -0.5334 -0.254)
				(xy -0.5334 -0.2794) (xy 0.5334 -0.2794) (xy 0.5334 -0.254) (xy 0.635 -0.254) (xy 0.635 0.254) (xy 0.5334 0.254)
				(xy 0.5334 0.2794)
			)
			(stroke
				(width 0)
				(type default)
			)
			(fill no)
			(layer "F.CrtYd")
		)
		(pad "1" smd rect
			(at 0.40005 0 270)
			(size 0.4572 0.508)
			(layers "F.Cu" "F.Mask" "F.Paste")
			(net "XDP_CPU_NODE1_PREQ_L")
		)
		(pad "2" smd rect
			(at -0.40005 0 270)
			(size 0.4572 0.508)
			(layers "F.Cu" "F.Mask" "F.Paste")
			(net "P1V05_NODE1")
		)
	)
	(footprint ""
		(layer "F.Cu")
		(at 24.032718 -149.117558 180)
		(property "Reference" "R564"
			(at 0.035306 1.198626 0)
			(unlocked yes)
			(layer "F.SilkS")
			(effects
				(font
					(size 0.7874 0.5842)
					(thickness 0.1524)
				)
			)
		)
		(property "Value" ""
			(at 0 0 180)
			(layer "F.Fab")
			(effects
				(font
					(size 1.27 1.27)
				)
			)
		)
		(duplicate_pad_numbers_are_jumpers no)
		(fp_line
			(start 1.2954 0.5842)
			(end -1.2954 0.5842)
			(stroke
				(width 0.1524)
				(type default)
			)
			(layer "F.SilkS")
		)
		(fp_line
			(start 1.2954 -0.5842)
			(end 1.2954 0.5842)
			(stroke
				(width 0.1524)
				(type default)
			)
			(layer "F.SilkS")
		)
		(fp_line
			(start -1.2954 0.5842)
			(end -1.2954 -0.5842)
			(stroke
				(width 0.1524)
				(type default)
			)
			(layer "F.SilkS")
		)
		(fp_line
			(start -1.2954 -0.5842)
			(end 1.2954 -0.5842)
			(stroke
				(width 0.1524)
				(type default)
			)
			(layer "F.SilkS")
		)
		(fp_poly
			(pts
				(xy 1.143 -0.3556) (xy 1.143 0.3556) (xy 0.8636 0.3556) (xy 0.8636 0.4572) (xy -0.8636 0.4572) (xy -0.8636 0.4318)
				(xy -0.8636 0.3556) (xy -1.143 0.3556) (xy -1.143 -0.3556) (xy -0.8636 -0.3556) (xy -0.8636 -0.4572)
				(xy 0.8636 -0.4572) (xy 0.8636 -0.3556)
			)
			(stroke
				(width 0)
				(type default)
			)
			(fill no)
			(layer "F.CrtYd")
		)
		(pad "1" smd rect
			(at 0.7366 0 270)
			(size 0.7112 0.8128)
			(layers "F.Cu" "F.Mask" "F.Paste")
			(net "P3V3_NODE1")
		)
		(pad "2" smd rect
			(at -0.7366 0 270)
			(size 0.7112 0.8128)
			(layers "F.Cu" "F.Mask" "F.Paste")
			(net "LAN1_CTRL_P1V9")
		)
	)
	(footprint ""
		(layer "F.Cu")
		(at 182.430674 -145.204942 -90)
		(property "Reference" "R594"
			(at -0.189738 2.185162 90)
			(unlocked yes)
			(layer "F.SilkS")
			(effects
				(font
					(size 0.7874 0.5842)
					(thickness 0.1524)
				)
			)
		)
		(property "Value" ""
			(at 0 0 270)
			(layer "F.Fab")
			(effects
				(font
					(size 1.27 1.27)
				)
			)
		)
		(duplicate_pad_numbers_are_jumpers no)
		(fp_line
			(start -1.2954 0.5842)
			(end -1.2954 -0.5842)
			(stroke
				(width 0.1524)
				(type default)
			)
			(layer "F.SilkS")
		)
		(fp_line
			(start 1.2954 0.5842)
			(end -1.2954 0.5842)
			(stroke
				(width 0.1524)
				(type default)
			)
			(layer "F.SilkS")
		)
		(fp_line
			(start -1.2954 -0.5842)
			(end 1.2954 -0.5842)
			(stroke
				(width 0.1524)
				(type default)
			)
			(layer "F.SilkS")
		)
		(fp_line
			(start 1.2954 -0.5842)
			(end 1.2954 0.5842)
			(stroke
				(width 0.1524)
				(type default)
			)
			(layer "F.SilkS")
		)
		(fp_poly
			(pts
				(xy 1.143 -0.3556) (xy 1.143 0.3556) (xy 0.8636 0.3556) (xy 0.8636 0.4572) (xy -0.8636 0.4572) (xy -0.8636 0.4318)
				(xy -0.8636 0.3556) (xy -1.143 0.3556) (xy -1.143 -0.3556) (xy -0.8636 -0.3556) (xy -0.8636 -0.4572)
				(xy 0.8636 -0.4572) (xy 0.8636 -0.3556)
			)
			(stroke
				(width 0)
				(type default)
			)
			(fill no)
			(layer "F.CrtYd")
		)
		(pad "1" smd rect
			(at 0.7366 0)
			(size 0.7112 0.8128)
			(layers "F.Cu" "F.Mask" "F.Paste")
			(net "P3V3_NODE1")
		)
		(pad "2" smd rect
			(at -0.7366 0)
			(size 0.7112 0.8128)
			(layers "F.Cu" "F.Mask" "F.Paste")
			(net "LAN2_CTRL_P1V9")
		)
	)
	(footprint ""
		(layer "F.Cu")
		(at 76.81976 -188.126624 90)
		(property "Reference" "C698"
			(at 4.548886 -1.419098 90)
			(unlocked yes)
			(layer "F.SilkS")
			(effects
				(font
					(size 0.7874 0.5842)
					(thickness 0.1524)
				)
				(justify left)
			)
		)
		(property "Value" ""
			(at 0 0 90)
			(layer "F.Fab")
			(effects
				(font
					(size 1.27 1.27)
				)
			)
		)
		(duplicate_pad_numbers_are_jumpers no)
		(fp_line
			(start 0.7874 -0.4064)
			(end 0.7874 0.4064)
			(stroke
				(width 0.1524)
				(type default)
			)
			(layer "F.SilkS")
		)
		(fp_line
			(start -0.7874 -0.4064)
			(end 0.7874 -0.4064)
			(stroke
				(width 0.1524)
				(type default)
			)
			(layer "F.SilkS")
		)
		(fp_line
			(start 0 0.381)
			(end 0 -0.381)
			(stroke
				(width 0.1524)
				(type default)
			)
			(layer "F.SilkS")
		)
		(fp_line
			(start 0.7874 0.4064)
			(end -0.7874 0.4064)
			(stroke
				(width 0.1524)
				(type default)
			)
			(layer "F.SilkS")
		)
		(fp_line
			(start -0.7874 0.4064)
			(end -0.7874 -0.4064)
			(stroke
				(width 0.1524)
				(type default)
			)
			(layer "F.SilkS")
		)
		(fp_poly
			(pts
				(xy -0.5334 0.254) (xy -0.635 0.254) (xy -0.635 0.2286) (xy -0.635 -0.254) (xy -0.5334 -0.254) (xy -0.5334 -0.2794)
				(xy 0.5334 -0.2794) (xy 0.5334 -0.254) (xy 0.635 -0.254) (xy 0.635 0.254) (xy 0.5334 0.254) (xy 0.5334 0.2794)
				(xy -0.508 0.2794) (xy -0.5334 0.2794)
			)
			(stroke
				(width 0)
				(type default)
			)
			(fill no)
			(layer "F.CrtYd")
		)
		(pad "1" smd rect
			(at 0.40005 0 90)
			(size 0.4572 0.508)
			(layers "F.Cu" "F.Mask" "F.Paste")
			(net "UART_T4_NODE1_TXD_R")
		)
		(pad "2" smd rect
			(at -0.40005 0 90)
			(size 0.4572 0.508)
			(layers "F.Cu" "F.Mask" "F.Paste")
			(net "GND")
		)
	)
	(footprint ""
		(layer "F.Cu")
		(at 75.474068 -94.131892 -90)
		(property "Reference" "R160"
			(at 55.53329 -24.083264 90)
			(unlocked yes)
			(layer "F.SilkS")
			(effects
				(font
					(size 0.7874 0.5842)
					(thickness 0.1524)
				)
				(justify left)
			)
		)
		(property "Value" ""
			(at 0 0 270)
			(layer "F.Fab")
			(effects
				(font
					(size 1.27 1.27)
				)
			)
		)
		(duplicate_pad_numbers_are_jumpers no)
		(fp_line
			(start -0.7874 0.4064)
			(end -0.7874 -0.4064)
			(stroke
				(width 0.1524)
				(type default)
			)
			(layer "F.SilkS")
		)
		(fp_line
			(start 0.7874 0.4064)
			(end -0.7874 0.4064)
			(stroke
				(width 0.1524)
				(type default)
			)
			(layer "F.SilkS")
		)
		(fp_line
			(start -0.7874 -0.4064)
			(end 0.7874 -0.4064)
			(stroke
				(width 0.1524)
				(type default)
			)
			(layer "F.SilkS")
		)
		(fp_line
			(start 0.7874 -0.4064)
			(end 0.7874 0.4064)
			(stroke
				(width 0.1524)
				(type default)
			)
			(layer "F.SilkS")
		)
		(fp_poly
			(pts
				(xy -0.508 0.2794) (xy -0.508 0.2286) (xy -0.635 0.2286) (xy -0.635 -0.254) (xy -0.5334 -0.254)
				(xy -0.5334 -0.2794) (xy 0.5334 -0.2794) (xy 0.5334 -0.254) (xy 0.635 -0.254) (xy 0.635 0.254) (xy 0.5334 0.254)
				(xy 0.5334 0.2794)
			)
			(stroke
				(width 0)
				(type default)
			)
			(fill no)
			(layer "F.CrtYd")
		)
		(pad "1" smd rect
			(at 0.40005 0 270)
			(size 0.4572 0.508)
			(layers "F.Cu" "F.Mask" "F.Paste")
			(net "PD_CPU_NODE1_NODE_ID")
		)
		(pad "2" smd rect
			(at -0.40005 0 270)
			(size 0.4572 0.508)
			(layers "F.Cu" "F.Mask" "F.Paste")
			(net "GND")
		)
	)
)
